# S9S_MB_2U (Grand Teton) — schematic netlist excerpt (pin names and nets, part order shuffled) for the footprints in the layout excerpt that follows; sources: Cadence DE-HDL packaged netlist, KiCad conversion of 03242023_DA0F0TMBIJ0_F0T_Motherboard_J_brd_V01_OCP.brd

R4696  Q_RES  0 5% CHIP  pkg 0402LF  page 305 : A = SMB_SML1_PMBUS_HSC_SDA ; B = SMB_SML1_PMBUS_HSC_MODULE_SDA
C166  Q_CAP_DIFFBUS  DIFF BUS_0.22UF 6.3V 20% X6S  pkg C0201  page 178 : \1\ = DMI_CPU0_PCH_RX_C_DP<2> ; \2\ = DMI_CPU0_PCH_RX_DP<2>
C48  Q_CAP  10UF 16V 10% X6S  pkg C0805  page 97 : A = P12V_S3_AUX_CPU0_NVDIMM ; B = GND

(kicad_pcb
	(version 20260206)
	(generator "pcbnew")
	(generator_version "10.0")
	(general
		(thickness 1.6)
		(legacy_teardrops no)
	)
	(paper "A4")
	(title_block
		(title "03242023_DA0F0TMBIJ0_F0T_Motherboard_J_brd_V01_OCP.brd")
		(comment 1 "Grand Teton / footprints 5624-5626 of 6105")
	)
	(layers
		(0 "F.Cu" signal "TOP")
		(4 "In1.Cu" signal "GND")
		(6 "In2.Cu" signal "IN1")
		(8 "In3.Cu" signal "GND1")
		(10 "In4.Cu" signal "IN2")
		(12 "In5.Cu" signal "GND2")
		(14 "In6.Cu" signal "IN3")
		(16 "In7.Cu" signal "GND3")
		(18 "In8.Cu" signal "VCC")
		(20 "In9.Cu" signal "VCC1")
		(22 "In10.Cu" signal "GND4")
		(24 "In11.Cu" signal "IN4")
		(26 "In12.Cu" signal "GND5")
		(28 "In13.Cu" signal "IN5")
		(30 "In14.Cu" signal "GND6")
		(32 "In15.Cu" signal "IN6")
		(34 "In16.Cu" signal "GND7")
		(2 "B.Cu" signal "BOTTOM")
		(9 "F.Adhes" user "F.Adhesive")
		(11 "B.Adhes" user "B.Adhesive")
		(13 "F.Paste" user "Package Geometry/Pastemask Top")
		(15 "B.Paste" user "Package Geometry/Pastemask Bottom")
		(5 "F.SilkS" user "Ref Des/Silkscreen Top")
		(7 "B.SilkS" user "Ref Des/Silkscreen Bottom")
		(1 "F.Mask" user "Board Geometry/Soldermask Top")
		(3 "B.Mask" user "Board Geometry/Soldermask Bottom")
		(17 "Dwgs.User" user "User.Drawings")
		(19 "Cmts.User" user "User.Comments")
		(21 "Eco1.User" user "User.Eco1")
		(23 "Eco2.User" user "User.Eco2")
		(25 "Edge.Cuts" user "Board Geometry/Outline")
		(27 "Margin" user)
		(31 "F.CrtYd" user "Package Geometry/Place Bound Top")
		(29 "B.CrtYd" user "Package Geometry/Place Bound Bottom")
		(35 "F.Fab" user "Ref Des/Assembly Top")
		(33 "B.Fab" user "Ref Des/Assembly Bottom")
	)
	(footprint ""
		(layer "B.Cu")
		(at 179.87645 -408.256994 90)
		(property "Reference" "R4696"
			(at 0 0 90)
			(layer "B.SilkS")
			(hide yes)
			(effects
				(font
					(size 1.27 1.27)
				)
				(justify mirror)
			)
		)
		(property "Value" ""
			(at 0 0 90)
			(layer "B.Fab")
			(effects
				(font
					(size 1.27 1.27)
				)
				(justify mirror)
			)
		)
		(duplicate_pad_numbers_are_jumpers no)
		(fp_line
			(start 0.7874 -0.4064)
			(end -0.7874 -0.4064)
			(stroke
				(width 0.1524)
				(type default)
			)
			(layer "B.SilkS")
		)
		(fp_line
			(start -0.7874 -0.4064)
			(end -0.7874 0.4064)
			(stroke
				(width 0.1524)
				(type default)
			)
			(layer "B.SilkS")
		)
		(fp_line
			(start 0.7874 0.4064)
			(end 0.7874 -0.4064)
			(stroke
				(width 0.1524)
				(type default)
			)
			(layer "B.SilkS")
		)
		(fp_line
			(start -0.7874 0.4064)
			(end 0.7874 0.4064)
			(stroke
				(width 0.1524)
				(type default)
			)
			(layer "B.SilkS")
		)
		(fp_line
			(start 0.67945 -0.305054)
			(end 0.12065 -0.305054)
			(stroke
				(width 0.1)
				(type default)
			)
			(layer "B.Fab")
		)
		(fp_line
			(start 0.12065 -0.305054)
			(end 0.12065 -0.2794)
			(stroke
				(width 0.1)
				(type default)
			)
			(layer "B.Fab")
		)
		(fp_line
			(start -0.12065 -0.3048)
			(end -0.67945 -0.3048)
			(stroke
				(width 0.1)
				(type default)
			)
			(layer "B.Fab")
		)
		(fp_line
			(start -0.67945 -0.3048)
			(end -0.67945 0.3048)
			(stroke
				(width 0.1)
				(type default)
			)
			(layer "B.Fab")
		)
		(fp_line
			(start 0.12065 -0.2794)
			(end -0.12065 -0.2794)
			(stroke
				(width 0.1)
				(type default)
			)
			(layer "B.Fab")
		)
		(fp_line
			(start -0.12065 -0.2794)
			(end -0.12065 -0.3048)
			(stroke
				(width 0.1)
				(type default)
			)
			(layer "B.Fab")
		)
		(fp_line
			(start 0.12065 0.2794)
			(end 0.12065 0.3048)
			(stroke
				(width 0.1)
				(type default)
			)
			(layer "B.Fab")
		)
		(fp_line
			(start -0.120396 0.2794)
			(end 0.12065 0.2794)
			(stroke
				(width 0.1)
				(type default)
			)
			(layer "B.Fab")
		)
		(fp_line
			(start 0.67945 0.3048)
			(end 0.67945 -0.305054)
			(stroke
				(width 0.1)
				(type default)
			)
			(layer "B.Fab")
		)
		(fp_line
			(start 0.12065 0.3048)
			(end 0.67945 0.3048)
			(stroke
				(width 0.1)
				(type default)
			)
			(layer "B.Fab")
		)
		(fp_line
			(start -0.120396 0.3048)
			(end -0.120396 0.2794)
			(stroke
				(width 0.1)
				(type default)
			)
			(layer "B.Fab")
		)
		(fp_line
			(start -0.67945 0.3048)
			(end -0.120396 0.3048)
			(stroke
				(width 0.1)
				(type default)
			)
			(layer "B.Fab")
		)
		(pad "1" smd circle
			(at 0.40005 0 270)
			(size 0 0)
			(layers "B.Cu" "B.Mask" "B.Paste")
			(net "SMB_SML1_PMBUS_HSC_SDA")
		)
		(pad "2" smd circle
			(at -0.40005 0 270)
			(size 0 0)
			(layers "B.Cu" "B.Mask" "B.Paste")
			(net "SMB_SML1_PMBUS_HSC_MODULE_SDA")
		)
	)
	(footprint ""
		(layer "B.Cu")
		(at 456.092814 -321.549776 -90)
		(property "Reference" "C48"
			(at 0 0 90)
			(layer "B.SilkS")
			(hide yes)
			(effects
				(font
					(size 1.27 1.27)
				)
				(justify mirror)
			)
		)
		(property "Value" ""
			(at 0 0 90)
			(layer "B.Fab")
			(effects
				(font
					(size 1.27 1.27)
				)
				(justify mirror)
			)
		)
		(duplicate_pad_numbers_are_jumpers no)
		(fp_line
			(start -1.524 0.762)
			(end 1.524 0.762)
			(stroke
				(width 0.1524)
				(type default)
			)
			(layer "B.SilkS")
		)
		(fp_line
			(start 1.524 0.762)
			(end 1.524 -0.762)
			(stroke
				(width 0.1524)
				(type default)
			)
			(layer "B.SilkS")
		)
		(fp_line
			(start -1.524 -0.762)
			(end -1.524 0.762)
			(stroke
				(width 0.1524)
				(type default)
			)
			(layer "B.SilkS")
		)
		(fp_line
			(start 1.524 -0.762)
			(end -1.524 -0.762)
			(stroke
				(width 0.1524)
				(type default)
			)
			(layer "B.SilkS")
		)
		(fp_line
			(start -1.1049 0.724916)
			(end -1.1049 -0.724916)
			(stroke
				(width 0.1)
				(type default)
			)
			(layer "B.Fab")
		)
		(fp_line
			(start 1.1049 0.724916)
			(end -1.1049 0.724916)
			(stroke
				(width 0.1)
				(type default)
			)
			(layer "B.Fab")
		)
		(fp_line
			(start -1.1049 -0.724916)
			(end 1.1049 -0.724916)
			(stroke
				(width 0.1)
				(type default)
			)
			(layer "B.Fab")
		)
		(fp_line
			(start 1.1049 -0.724916)
			(end 1.1049 0.724916)
			(stroke
				(width 0.1)
				(type default)
			)
			(layer "B.Fab")
		)
		(pad "1" smd rect
			(at 0.889 0 270)
			(size 1.016 1.27)
			(layers "B.Cu" "B.Mask" "B.Paste")
			(net "P12V_S3_AUX_CPU0_NVDIMM")
		)
		(pad "2" smd rect
			(at -0.889 0 270)
			(size 1.016 1.27)
			(layers "B.Cu" "B.Mask" "B.Paste")
			(net "GND")
		)
	)
	(footprint ""
		(layer "B.Cu")
		(at 341.320628 -62.056264 90)
		(property "Reference" "C166"
			(at 0 0 90)
			(layer "B.SilkS")
			(hide yes)
			(effects
				(font
					(size 1.27 1.27)
				)
				(justify mirror)
			)
		)
		(property "Value" ""
			(at 0 0 90)
			(layer "B.Fab")
			(effects
				(font
					(size 1.27 1.27)
				)
				(justify mirror)
			)
		)
		(duplicate_pad_numbers_are_jumpers no)
		(fp_line
			(start 0.299974 -0.150114)
			(end -0.299974 -0.150114)
			(stroke
				(width 0.1)
				(type default)
			)
			(layer "B.Fab")
		)
		(fp_line
			(start -0.299974 -0.150114)
			(end -0.299974 0.150114)
			(stroke
				(width 0.1)
				(type default)
			)
			(layer "B.Fab")
		)
		(fp_line
			(start 0.299974 0.150114)
			(end 0.299974 -0.150114)
			(stroke
				(width 0.1)
				(type default)
			)
			(layer "B.Fab")
		)
		(fp_line
			(start -0.299974 0.150114)
			(end 0.299974 0.150114)
			(stroke
				(width 0.1)
				(type default)
			)
			(layer "B.Fab")
		)
		(pad "1" smd rect
			(at 0.2667 0 270)
			(size 0.3048 0.381)
			(layers "B.Cu" "B.Mask" "B.Paste")
			(net "DMI_CPU0_PCH_RX_C_DP<2>")
		)
		(pad "2" smd rect
			(at -0.2667 0 270)
			(size 0.3048 0.381)
			(layers "B.Cu" "B.Mask" "B.Paste")
			(net "DMI_CPU0_PCH_RX_DP<2>")
		)
	)
)
